(kicad_pcb
	(version 20260206)
	(generator "pcbnew")
	(generator_version "10.0")
	(general
		(thickness 1.6)
		(legacy_teardrops no)
	)
	(paper "A4")
	(title_block
		(title "panther-plus-userver — 13130-1b_20150205.brd")
		(comment 1 "Honey Badger (Wiwynn) / footprint 894 of 1509 (DIMM1), pads 191-197 of 210")
	)
	(layers
		(0 "F.Cu" signal "TOP")
		(4 "In1.Cu" signal "L2")
		(6 "In2.Cu" signal "L3")
		(8 "In3.Cu" signal "L4")
		(10 "In4.Cu" signal "L5")
		(12 "In5.Cu" signal "L6")
		(14 "In6.Cu" signal "L7")
		(16 "In7.Cu" signal "L8")
		(18 "In8.Cu" signal "L9")
		(20 "In9.Cu" signal "L10")
		(22 "In10.Cu" signal "L11")
		(2 "B.Cu" signal "BOTTOM")
		(9 "F.Adhes" user "F.Adhesive")
		(11 "B.Adhes" user "B.Adhesive")
		(13 "F.Paste" user "Package Geometry/Pastemask Top")
		(15 "B.Paste" user "Package Geometry/Pastemask Bottom")
		(5 "F.SilkS" user "Ref Des/Silkscreen Top")
		(7 "B.SilkS" user "Ref Des/Silkscreen Bottom")
		(1 "F.Mask" user "Board Geometry/Soldermask Top")
		(3 "B.Mask" user "Board Geometry/Soldermask Bottom")
		(17 "Dwgs.User" user "User.Drawings")
		(19 "Cmts.User" user "User.Comments")
		(21 "Eco1.User" user "User.Eco1")
		(23 "Eco2.User" user "User.Eco2")
		(25 "Edge.Cuts" user "Board Geometry/Outline")
		(27 "Margin" user)
		(31 "F.CrtYd" user "Package Geometry/Place Bound Top")
		(29 "B.CrtYd" user "Package Geometry/Place Bound Bottom")
		(35 "F.Fab" user "Ref Des/Assembly Top")
		(33 "B.Fab" user "Ref Des/Assembly Bottom")
	)
	(footprint ""
		(layer "B.Cu")
		(at 158.500064 -66.699892 180)
		(property "Reference" "DIMM1"
			(at 0 0 0)
			(layer "B.SilkS")
			(hide yes)
			(effects
				(font
					(size 1.27 1.27)
				)
				(justify mirror)
			)
		)
		(property "Value" "DDR3-204P-142-COLAY-1-GP-U"
			(at 41.312338 -16.676878 180)
			(unlocked yes)
			(layer "B.Fab")
			(hide yes)
			(effects
				(font
					(size 1.016 1.016)
					(thickness 0.1524)
				)
				(justify mirror)
			)
		)
		(property "Device Type" "AS0A626-J8R6-7H-COLAY-1"
			(at 41.312338 -18.200878 180)
			(unlocked yes)
			(layer "B.Fab")
			(hide yes)
			(effects
				(font
					(size 1.016 1.016)
					(thickness 0.1524)
				)
				(justify mirror)
			)
		)
		(duplicate_pad_numbers_are_jumpers no)
		(pad "189" smd custom
			(at 27.15006 -4.100068)
			(size 0.1143 0.1143)
			(layers "B.Cu" "B.Mask" "B.Paste")
			(net "GND")
			(options
				(clearance outline)
				(anchor circle)
			)
			(primitives
				(gr_poly
					(pts
						(xy 0 -0.9017) (xy -0.03175 -0.89916) (xy -0.0635 -0.889) (xy -0.09144 -0.87376) (xy -0.11684 -0.85344)
						(xy -0.13716 -0.82804) (xy -0.1524 -0.8001) (xy -0.16256 -0.76835) (xy -0.1651 -0.7366) (xy -0.1651 -0.44958)
						(xy -0.17272 -0.44196) (xy -0.19812 -0.4064) (xy -0.2032 -0.39624) (xy -0.20701 -0.38735) (xy -0.21209 -0.37719)
						(xy -0.2159 -0.36703) (xy -0.21844 -0.35687) (xy -0.22225 -0.34544) (xy -0.22352 -0.33528) (xy -0.22606 -0.32512)
						(xy -0.22733 -0.31369) (xy -0.22733 -0.30353) (xy -0.2286 -0.2921) (xy -0.22733 -0.28067) (xy -0.22733 -0.27051)
						(xy -0.22606 -0.25908) (xy -0.22352 -0.24892) (xy -0.22225 -0.23876) (xy -0.21844 -0.22733) (xy -0.2159 -0.21717)
						(xy -0.21209 -0.20701) (xy -0.20701 -0.19685) (xy -0.2032 -0.18796) (xy -0.19812 -0.1778) (xy -0.17272 -0.14224)
						(xy -0.1651 -0.13462) (xy -0.1651 0.7366) (xy -0.16256 0.76835) (xy -0.1524 0.8001) (xy -0.13716 0.82804)
						(xy -0.11684 0.85344) (xy -0.09144 0.87376) (xy -0.0635 0.889) (xy -0.03175 0.89916) (xy 0 0.9017)
						(xy 0.03175 0.89916) (xy 0.0635 0.889) (xy 0.09144 0.87376) (xy 0.11684 0.85344) (xy 0.13716 0.82804)
						(xy 0.1524 0.8001) (xy 0.16256 0.76835) (xy 0.1651 0.7366) (xy 0.1651 -0.13462) (xy 0.17272 -0.14224)
						(xy 0.19812 -0.1778) (xy 0.2032 -0.18796) (xy 0.20701 -0.19685) (xy 0.21209 -0.20701) (xy 0.2159 -0.21717)
						(xy 0.21844 -0.22733) (xy 0.22225 -0.23876) (xy 0.22352 -0.24892) (xy 0.22606 -0.25908) (xy 0.22733 -0.27051)
						(xy 0.22733 -0.28067) (xy 0.2286 -0.2921) (xy 0.22733 -0.30353) (xy 0.22733 -0.31369) (xy 0.22606 -0.32512)
						(xy 0.22352 -0.33528) (xy 0.22225 -0.34544) (xy 0.21844 -0.35687) (xy 0.2159 -0.36703) (xy 0.21209 -0.37719)
						(xy 0.20701 -0.38735) (xy 0.2032 -0.39624) (xy 0.19812 -0.4064) (xy 0.17272 -0.44196) (xy 0.1651 -0.44958)
						(xy 0.1651 -0.7366) (xy 0.16256 -0.76835) (xy 0.1524 -0.8001) (xy 0.13716 -0.82804) (xy 0.11684 -0.85344)
						(xy 0.09144 -0.87376) (xy 0.0635 -0.889) (xy 0.03175 -0.89916)
					)
					(width 0)
					(fill yes)
				)
			)
		)
		(pad "190" smd custom
			(at 27.450034 4.100068)
			(size 0.1143 0.1143)
			(layers "B.Cu" "B.Mask" "B.Paste")
			(net "GND")
			(options
				(clearance outline)
				(anchor circle)
			)
			(primitives
				(gr_poly
					(pts
						(xy 0 -0.9017) (xy -0.03175 -0.89916) (xy -0.0635 -0.889) (xy -0.09144 -0.87376) (xy -0.11684 -0.85344)
						(xy -0.13716 -0.82804) (xy -0.1524 -0.8001) (xy -0.16256 -0.76835) (xy -0.1651 -0.7366) (xy -0.1651 0.13462)
						(xy -0.17272 0.14224) (xy -0.19812 0.1778) (xy -0.2032 0.18796) (xy -0.20701 0.19685) (xy -0.21209 0.20701)
						(xy -0.2159 0.21717) (xy -0.21844 0.22733) (xy -0.22225 0.23876) (xy -0.22352 0.24892) (xy -0.22606 0.25908)
						(xy -0.22733 0.27051) (xy -0.22733 0.28067) (xy -0.2286 0.2921) (xy -0.22733 0.30353) (xy -0.22733 0.31369)
						(xy -0.22606 0.32512) (xy -0.22352 0.33528) (xy -0.22225 0.34544) (xy -0.21844 0.35687) (xy -0.2159 0.36703)
						(xy -0.21209 0.37719) (xy -0.20701 0.38735) (xy -0.2032 0.39624) (xy -0.19812 0.4064) (xy -0.17272 0.44196)
						(xy -0.1651 0.44958) (xy -0.1651 0.7366) (xy -0.16256 0.76835) (xy -0.1524 0.8001) (xy -0.13716 0.82804)
						(xy -0.11684 0.85344) (xy -0.09144 0.87376) (xy -0.0635 0.889) (xy -0.03175 0.89916) (xy 0 0.9017)
						(xy 0.03175 0.89916) (xy 0.0635 0.889) (xy 0.09144 0.87376) (xy 0.11684 0.85344) (xy 0.13716 0.82804)
						(xy 0.1524 0.8001) (xy 0.16256 0.76835) (xy 0.1651 0.7366) (xy 0.1651 0.44958) (xy 0.17272 0.44196)
						(xy 0.19812 0.4064) (xy 0.2032 0.39624) (xy 0.20701 0.38735) (xy 0.21209 0.37719) (xy 0.2159 0.36703)
						(xy 0.21844 0.35687) (xy 0.22225 0.34544) (xy 0.22352 0.33528) (xy 0.22606 0.32512) (xy 0.22733 0.31369)
						(xy 0.22733 0.30353) (xy 0.2286 0.2921) (xy 0.22733 0.28067) (xy 0.22733 0.27051) (xy 0.22606 0.25908)
						(xy 0.22352 0.24892) (xy 0.22225 0.23876) (xy 0.21844 0.22733) (xy 0.2159 0.21717) (xy 0.21209 0.20701)
						(xy 0.20701 0.19685) (xy 0.2032 0.18796) (xy 0.19812 0.1778) (xy 0.17272 0.14224) (xy 0.1651 0.13462)
						(xy 0.1651 -0.7366) (xy 0.16256 -0.76835) (xy 0.1524 -0.8001) (xy 0.13716 -0.82804) (xy 0.11684 -0.85344)
						(xy 0.09144 -0.87376) (xy 0.0635 -0.889) (xy 0.03175 -0.89916)
					)
					(width 0)
					(fill yes)
				)
			)
		)
		(pad "191" smd custom
			(at 27.750008 -4.100068)
			(size 0.1143 0.1143)
			(layers "B.Cu" "B.Mask" "B.Paste")
			(net "M_A_DQ58")
			(options
				(clearance outline)
				(anchor circle)
			)
			(primitives
				(gr_poly
					(pts
						(xy 0 -0.9017) (xy -0.03175 -0.89916) (xy -0.0635 -0.889) (xy -0.09144 -0.87376) (xy -0.11684 -0.85344)
						(xy -0.13716 -0.82804) (xy -0.1524 -0.8001) (xy -0.16256 -0.76835) (xy -0.1651 -0.7366) (xy -0.1651 -0.19685)
						(xy -0.17272 -0.18923) (xy -0.17907 -0.18034) (xy -0.18669 -0.17145) (xy -0.19177 -0.16256) (xy -0.19812 -0.15367)
						(xy -0.20828 -0.13335) (xy -0.21971 -0.10287) (xy -0.22225 -0.09271) (xy -0.22479 -0.08128) (xy -0.22606 -0.07112)
						(xy -0.2286 -0.05969) (xy -0.2286 -0.01651) (xy -0.22606 -0.00508) (xy -0.22479 0.00508) (xy -0.22225 0.01651)
						(xy -0.21971 0.02667) (xy -0.20828 0.05715) (xy -0.19812 0.07747) (xy -0.19177 0.08636) (xy -0.18669 0.09525)
						(xy -0.17907 0.10414) (xy -0.17272 0.11303) (xy -0.1651 0.12065) (xy -0.1651 0.7366) (xy -0.16256 0.76835)
						(xy -0.1524 0.8001) (xy -0.13716 0.82804) (xy -0.11684 0.85344) (xy -0.09144 0.87376) (xy -0.0635 0.889)
						(xy -0.03175 0.89916) (xy 0 0.9017) (xy 0.03175 0.89916) (xy 0.0635 0.889) (xy 0.09144 0.87376)
						(xy 0.11684 0.85344) (xy 0.13716 0.82804) (xy 0.1524 0.8001) (xy 0.16256 0.76835) (xy 0.1651 0.7366)
						(xy 0.1651 0.11938) (xy 0.17272 0.11176) (xy 0.19812 0.0762) (xy 0.2032 0.06604) (xy 0.20701 0.05715)
						(xy 0.21209 0.04699) (xy 0.2159 0.03683) (xy 0.21844 0.02667) (xy 0.22225 0.01524) (xy 0.22352 0.00508)
						(xy 0.22606 -0.00508) (xy 0.22733 -0.01651) (xy 0.22733 -0.02667) (xy 0.2286 -0.0381) (xy 0.22733 -0.04953)
						(xy 0.22733 -0.05969) (xy 0.22606 -0.07112) (xy 0.22352 -0.08128) (xy 0.22225 -0.09144) (xy 0.21844 -0.10287)
						(xy 0.2159 -0.11303) (xy 0.21209 -0.12319) (xy 0.20701 -0.13335) (xy 0.2032 -0.14224) (xy 0.19812 -0.1524)
						(xy 0.17272 -0.18796) (xy 0.1651 -0.19558) (xy 0.1651 -0.7366) (xy 0.16256 -0.76835) (xy 0.1524 -0.8001)
						(xy 0.13716 -0.82804) (xy 0.11684 -0.85344) (xy 0.09144 -0.87376) (xy 0.0635 -0.889) (xy 0.03175 -0.89916)
					)
					(width 0)
					(fill yes)
				)
			)
		)
		(pad "192" smd custom
			(at 28.049982 4.100068)
			(size 0.1143 0.1143)
			(layers "B.Cu" "B.Mask" "B.Paste")
			(net "M_A_DQ62")
			(options
				(clearance outline)
				(anchor circle)
			)
			(primitives
				(gr_poly
					(pts
						(xy 0 -0.9017) (xy -0.03175 -0.89916) (xy -0.0635 -0.889) (xy -0.09144 -0.87376) (xy -0.11684 -0.85344)
						(xy -0.13716 -0.82804) (xy -0.1524 -0.8001) (xy -0.16256 -0.76835) (xy -0.1651 -0.7366) (xy -0.1651 -0.11938)
						(xy -0.17272 -0.11176) (xy -0.19812 -0.0762) (xy -0.2032 -0.06604) (xy -0.20701 -0.05715) (xy -0.21209 -0.04699)
						(xy -0.2159 -0.03683) (xy -0.21844 -0.02667) (xy -0.22225 -0.01524) (xy -0.22352 -0.00508) (xy -0.22606 0.00508)
						(xy -0.22733 0.01651) (xy -0.22733 0.02667) (xy -0.2286 0.0381) (xy -0.22733 0.04953) (xy -0.22733 0.05969)
						(xy -0.22606 0.07112) (xy -0.22352 0.08128) (xy -0.22225 0.09144) (xy -0.21844 0.10287) (xy -0.2159 0.11303)
						(xy -0.21209 0.12319) (xy -0.20701 0.13335) (xy -0.2032 0.14224) (xy -0.19812 0.1524) (xy -0.17272 0.18796)
						(xy -0.1651 0.19558) (xy -0.1651 0.7366) (xy -0.16256 0.76835) (xy -0.1524 0.8001) (xy -0.13716 0.82804)
						(xy -0.11684 0.85344) (xy -0.09144 0.87376) (xy -0.0635 0.889) (xy -0.03175 0.89916) (xy 0 0.9017)
						(xy 0.03175 0.89916) (xy 0.0635 0.889) (xy 0.09144 0.87376) (xy 0.11684 0.85344) (xy 0.13716 0.82804)
						(xy 0.1524 0.8001) (xy 0.16256 0.76835) (xy 0.1651 0.7366) (xy 0.1651 0.19685) (xy 0.17272 0.18923)
						(xy 0.17907 0.18034) (xy 0.18669 0.17145) (xy 0.19177 0.16256) (xy 0.19812 0.15367) (xy 0.20828 0.13335)
						(xy 0.21971 0.10287) (xy 0.22225 0.09271) (xy 0.22479 0.08128) (xy 0.22606 0.07112) (xy 0.2286 0.05969)
						(xy 0.2286 0.01651) (xy 0.22606 0.00508) (xy 0.22479 -0.00508) (xy 0.22225 -0.01651) (xy 0.21971 -0.02667)
						(xy 0.20828 -0.05715) (xy 0.19812 -0.07747) (xy 0.19177 -0.08636) (xy 0.18669 -0.09525) (xy 0.17907 -0.10414)
						(xy 0.17272 -0.11303) (xy 0.1651 -0.12065) (xy 0.1651 -0.7366) (xy 0.16256 -0.76835) (xy 0.1524 -0.8001)
						(xy 0.13716 -0.82804) (xy 0.11684 -0.85344) (xy 0.09144 -0.87376) (xy 0.0635 -0.889) (xy 0.03175 -0.89916)
					)
					(width 0)
					(fill yes)
				)
			)
		)
		(pad "193" smd custom
			(at 28.349956 -4.100068)
			(size 0.1143 0.1143)
			(layers "B.Cu" "B.Mask" "B.Paste")
			(net "M_A_DQ59")
			(options
				(clearance outline)
				(anchor circle)
			)
			(primitives
				(gr_poly
					(pts
						(xy 0 -0.9017) (xy -0.03175 -0.89916) (xy -0.0635 -0.889) (xy -0.09144 -0.87376) (xy -0.11684 -0.85344)
						(xy -0.13716 -0.82804) (xy -0.1524 -0.8001) (xy -0.16256 -0.76835) (xy -0.1651 -0.7366) (xy -0.1651 -0.44958)
						(xy -0.17272 -0.44196) (xy -0.19812 -0.4064) (xy -0.2032 -0.39624) (xy -0.20701 -0.38735) (xy -0.21209 -0.37719)
						(xy -0.2159 -0.36703) (xy -0.21844 -0.35687) (xy -0.22225 -0.34544) (xy -0.22352 -0.33528) (xy -0.22606 -0.32512)
						(xy -0.22733 -0.31369) (xy -0.22733 -0.30353) (xy -0.2286 -0.2921) (xy -0.22733 -0.28067) (xy -0.22733 -0.27051)
						(xy -0.22606 -0.25908) (xy -0.22352 -0.24892) (xy -0.22225 -0.23876) (xy -0.21844 -0.22733) (xy -0.2159 -0.21717)
						(xy -0.21209 -0.20701) (xy -0.20701 -0.19685) (xy -0.2032 -0.18796) (xy -0.19812 -0.1778) (xy -0.17272 -0.14224)
						(xy -0.1651 -0.13462) (xy -0.1651 0.7366) (xy -0.16256 0.76835) (xy -0.1524 0.8001) (xy -0.13716 0.82804)
						(xy -0.11684 0.85344) (xy -0.09144 0.87376) (xy -0.0635 0.889) (xy -0.03175 0.89916) (xy 0 0.9017)
						(xy 0.03175 0.89916) (xy 0.0635 0.889) (xy 0.09144 0.87376) (xy 0.11684 0.85344) (xy 0.13716 0.82804)
						(xy 0.1524 0.8001) (xy 0.16256 0.76835) (xy 0.1651 0.7366) (xy 0.1651 -0.13462) (xy 0.17272 -0.14224)
						(xy 0.19812 -0.1778) (xy 0.2032 -0.18796) (xy 0.20701 -0.19685) (xy 0.21209 -0.20701) (xy 0.2159 -0.21717)
						(xy 0.21844 -0.22733) (xy 0.22225 -0.23876) (xy 0.22352 -0.24892) (xy 0.22606 -0.25908) (xy 0.22733 -0.27051)
						(xy 0.22733 -0.28067) (xy 0.2286 -0.2921) (xy 0.22733 -0.30353) (xy 0.22733 -0.31369) (xy 0.22606 -0.32512)
						(xy 0.22352 -0.33528) (xy 0.22225 -0.34544) (xy 0.21844 -0.35687) (xy 0.2159 -0.36703) (xy 0.21209 -0.37719)
						(xy 0.20701 -0.38735) (xy 0.2032 -0.39624) (xy 0.19812 -0.4064) (xy 0.17272 -0.44196) (xy 0.1651 -0.44958)
						(xy 0.1651 -0.7366) (xy 0.16256 -0.76835) (xy 0.1524 -0.8001) (xy 0.13716 -0.82804) (xy 0.11684 -0.85344)
						(xy 0.09144 -0.87376) (xy 0.0635 -0.889) (xy 0.03175 -0.89916)
					)
					(width 0)
					(fill yes)
				)
			)
		)
		(pad "194" smd custom
			(at 28.64993 4.100068)
			(size 0.1143 0.1143)
			(layers "B.Cu" "B.Mask" "B.Paste")
			(net "M_A_DQ63")
			(options
				(clearance outline)
				(anchor circle)
			)
			(primitives
				(gr_poly
					(pts
						(xy 0 -0.9017) (xy -0.03175 -0.89916) (xy -0.0635 -0.889) (xy -0.09144 -0.87376) (xy -0.11684 -0.85344)
						(xy -0.13716 -0.82804) (xy -0.1524 -0.8001) (xy -0.16256 -0.76835) (xy -0.1651 -0.7366) (xy -0.1651 0.13462)
						(xy -0.17272 0.14224) (xy -0.19812 0.1778) (xy -0.2032 0.18796) (xy -0.20701 0.19685) (xy -0.21209 0.20701)
						(xy -0.2159 0.21717) (xy -0.21844 0.22733) (xy -0.22225 0.23876) (xy -0.22352 0.24892) (xy -0.22606 0.25908)
						(xy -0.22733 0.27051) (xy -0.22733 0.28067) (xy -0.2286 0.2921) (xy -0.22733 0.30353) (xy -0.22733 0.31369)
						(xy -0.22606 0.32512) (xy -0.22352 0.33528) (xy -0.22225 0.34544) (xy -0.21844 0.35687) (xy -0.2159 0.36703)
						(xy -0.21209 0.37719) (xy -0.20701 0.38735) (xy -0.2032 0.39624) (xy -0.19812 0.4064) (xy -0.17272 0.44196)
						(xy -0.1651 0.44958) (xy -0.1651 0.7366) (xy -0.16256 0.76835) (xy -0.1524 0.8001) (xy -0.13716 0.82804)
						(xy -0.11684 0.85344) (xy -0.09144 0.87376) (xy -0.0635 0.889) (xy -0.03175 0.89916) (xy 0 0.9017)
						(xy 0.03175 0.89916) (xy 0.0635 0.889) (xy 0.09144 0.87376) (xy 0.11684 0.85344) (xy 0.13716 0.82804)
						(xy 0.1524 0.8001) (xy 0.16256 0.76835) (xy 0.1651 0.7366) (xy 0.1651 0.44958) (xy 0.17272 0.44196)
						(xy 0.19812 0.4064) (xy 0.2032 0.39624) (xy 0.20701 0.38735) (xy 0.21209 0.37719) (xy 0.2159 0.36703)
						(xy 0.21844 0.35687) (xy 0.22225 0.34544) (xy 0.22352 0.33528) (xy 0.22606 0.32512) (xy 0.22733 0.31369)
						(xy 0.22733 0.30353) (xy 0.2286 0.2921) (xy 0.22733 0.28067) (xy 0.22733 0.27051) (xy 0.22606 0.25908)
						(xy 0.22352 0.24892) (xy 0.22225 0.23876) (xy 0.21844 0.22733) (xy 0.2159 0.21717) (xy 0.21209 0.20701)
						(xy 0.20701 0.19685) (xy 0.2032 0.18796) (xy 0.19812 0.1778) (xy 0.17272 0.14224) (xy 0.1651 0.13462)
						(xy 0.1651 -0.7366) (xy 0.16256 -0.76835) (xy 0.1524 -0.8001) (xy 0.13716 -0.82804) (xy 0.11684 -0.85344)
						(xy 0.09144 -0.87376) (xy 0.0635 -0.889) (xy 0.03175 -0.89916)
					)
					(width 0)
					(fill yes)
				)
			)
		)
		(pad "195" smd custom
			(at 28.949904 -4.100068)
			(size 0.1143 0.1143)
			(layers "B.Cu" "B.Mask" "B.Paste")
			(net "GND")
			(options
				(clearance outline)
				(anchor circle)
			)
			(primitives
				(gr_poly
					(pts
						(xy 0 -0.9017) (xy -0.03175 -0.89916) (xy -0.0635 -0.889) (xy -0.09144 -0.87376) (xy -0.11684 -0.85344)
						(xy -0.13716 -0.82804) (xy -0.1524 -0.8001) (xy -0.16256 -0.76835) (xy -0.1651 -0.7366) (xy -0.1651 -0.19685)
						(xy -0.17272 -0.18923) (xy -0.17907 -0.18034) (xy -0.18669 -0.17145) (xy -0.19177 -0.16256) (xy -0.19812 -0.15367)
						(xy -0.20828 -0.13335) (xy -0.21971 -0.10287) (xy -0.22225 -0.09271) (xy -0.22479 -0.08128) (xy -0.22606 -0.07112)
						(xy -0.2286 -0.05969) (xy -0.2286 -0.01651) (xy -0.22606 -0.00508) (xy -0.22479 0.00508) (xy -0.22225 0.01651)
						(xy -0.21971 0.02667) (xy -0.20828 0.05715) (xy -0.19812 0.07747) (xy -0.19177 0.08636) (xy -0.18669 0.09525)
						(xy -0.17907 0.10414) (xy -0.17272 0.11303) (xy -0.1651 0.12065) (xy -0.1651 0.7366) (xy -0.16256 0.76835)
						(xy -0.1524 0.8001) (xy -0.13716 0.82804) (xy -0.11684 0.85344) (xy -0.09144 0.87376) (xy -0.0635 0.889)
						(xy -0.03175 0.89916) (xy 0 0.9017) (xy 0.03175 0.89916) (xy 0.0635 0.889) (xy 0.09144 0.87376)
						(xy 0.11684 0.85344) (xy 0.13716 0.82804) (xy 0.1524 0.8001) (xy 0.16256 0.76835) (xy 0.1651 0.7366)
						(xy 0.1651 0.11938) (xy 0.17272 0.11176) (xy 0.19812 0.0762) (xy 0.2032 0.06604) (xy 0.20701 0.05715)
						(xy 0.21209 0.04699) (xy 0.2159 0.03683) (xy 0.21844 0.02667) (xy 0.22225 0.01524) (xy 0.22352 0.00508)
						(xy 0.22606 -0.00508) (xy 0.22733 -0.01651) (xy 0.22733 -0.02667) (xy 0.2286 -0.0381) (xy 0.22733 -0.04953)
						(xy 0.22733 -0.05969) (xy 0.22606 -0.07112) (xy 0.22352 -0.08128) (xy 0.22225 -0.09144) (xy 0.21844 -0.10287)
						(xy 0.2159 -0.11303) (xy 0.21209 -0.12319) (xy 0.20701 -0.13335) (xy 0.2032 -0.14224) (xy 0.19812 -0.1524)
						(xy 0.17272 -0.18796) (xy 0.1651 -0.19558) (xy 0.1651 -0.7366) (xy 0.16256 -0.76835) (xy 0.1524 -0.8001)
						(xy 0.13716 -0.82804) (xy 0.11684 -0.85344) (xy 0.09144 -0.87376) (xy 0.0635 -0.889) (xy 0.03175 -0.89916)
					)
					(width 0)
					(fill yes)
				)
			)
		)
	)
)
